(kicad_pcb
	(version 20260206)
	(generator "pcbnew")
	(generator_version "10.0")
	(general
		(thickness 1.6)
		(legacy_teardrops no)
	)
	(paper "A4")
	(title_block
		(title "03242023_DA0F0TMBIJ0_F0T_Motherboard_J_brd_V01_OCP.brd")
		(comment 1 "Grand Teton / footprints 3134-3140 of 6105")
	)
	(layers
		(0 "F.Cu" signal "TOP")
		(4 "In1.Cu" signal "GND")
		(6 "In2.Cu" signal "IN1")
		(8 "In3.Cu" signal "GND1")
		(10 "In4.Cu" signal "IN2")
		(12 "In5.Cu" signal "GND2")
		(14 "In6.Cu" signal "IN3")
		(16 "In7.Cu" signal "GND3")
		(18 "In8.Cu" signal "VCC")
		(20 "In9.Cu" signal "VCC1")
		(22 "In10.Cu" signal "GND4")
		(24 "In11.Cu" signal "IN4")
		(26 "In12.Cu" signal "GND5")
		(28 "In13.Cu" signal "IN5")
		(30 "In14.Cu" signal "GND6")
		(32 "In15.Cu" signal "IN6")
		(34 "In16.Cu" signal "GND7")
		(2 "B.Cu" signal "BOTTOM")
		(9 "F.Adhes" user "F.Adhesive")
		(11 "B.Adhes" user "B.Adhesive")
		(13 "F.Paste" user "Package Geometry/Pastemask Top")
		(15 "B.Paste" user "Package Geometry/Pastemask Bottom")
		(5 "F.SilkS" user "Ref Des/Silkscreen Top")
		(7 "B.SilkS" user "Ref Des/Silkscreen Bottom")
		(1 "F.Mask" user "Board Geometry/Soldermask Top")
		(3 "B.Mask" user "Board Geometry/Soldermask Bottom")
		(17 "Dwgs.User" user "User.Drawings")
		(19 "Cmts.User" user "User.Comments")
		(21 "Eco1.User" user "User.Eco1")
		(23 "Eco2.User" user "User.Eco2")
		(25 "Edge.Cuts" user "Board Geometry/Outline")
		(27 "Margin" user)
		(31 "F.CrtYd" user "Package Geometry/Place Bound Top")
		(29 "B.CrtYd" user "Package Geometry/Place Bound Bottom")
		(35 "F.Fab" user "Ref Des/Assembly Top")
		(33 "B.Fab" user "Ref Des/Assembly Bottom")
	)
	(footprint ""
		(layer "F.Cu")
		(at 406.124664 -368.826034)
		(property "Reference" "R334"
			(at 0 0 0)
			(layer "F.SilkS")
			(hide yes)
			(effects
				(font
					(size 1.27 1.27)
				)
			)
		)
		(property "Value" ""
			(at 0 0 0)
			(layer "F.Fab")
			(effects
				(font
					(size 1.27 1.27)
				)
			)
		)
		(duplicate_pad_numbers_are_jumpers no)
		(fp_line
			(start -0.7874 -0.4064)
			(end 0.7874 -0.4064)
			(stroke
				(width 0.1524)
				(type default)
			)
			(layer "F.SilkS")
		)
		(fp_line
			(start -0.7874 0.4064)
			(end -0.7874 -0.4064)
			(stroke
				(width 0.1524)
				(type default)
			)
			(layer "F.SilkS")
		)
		(fp_line
			(start 0.7874 -0.4064)
			(end 0.7874 0.4064)
			(stroke
				(width 0.1524)
				(type default)
			)
			(layer "F.SilkS")
		)
		(fp_line
			(start 0.7874 0.4064)
			(end -0.7874 0.4064)
			(stroke
				(width 0.1524)
				(type default)
			)
			(layer "F.SilkS")
		)
		(fp_line
			(start -0.67945 -0.305054)
			(end -0.12065 -0.305054)
			(stroke
				(width 0.1)
				(type default)
			)
			(layer "F.Fab")
		)
		(fp_line
			(start -0.67945 0.3048)
			(end -0.67945 -0.305054)
			(stroke
				(width 0.1)
				(type default)
			)
			(layer "F.Fab")
		)
		(fp_line
			(start -0.12065 -0.305054)
			(end -0.12065 -0.2794)
			(stroke
				(width 0.1)
				(type default)
			)
			(layer "F.Fab")
		)
		(fp_line
			(start -0.12065 -0.2794)
			(end 0.12065 -0.2794)
			(stroke
				(width 0.1)
				(type default)
			)
			(layer "F.Fab")
		)
		(fp_line
			(start -0.12065 0.2794)
			(end -0.12065 0.3048)
			(stroke
				(width 0.1)
				(type default)
			)
			(layer "F.Fab")
		)
		(fp_line
			(start -0.12065 0.3048)
			(end -0.67945 0.3048)
			(stroke
				(width 0.1)
				(type default)
			)
			(layer "F.Fab")
		)
		(fp_line
			(start 0.120396 0.2794)
			(end -0.12065 0.2794)
			(stroke
				(width 0.1)
				(type default)
			)
			(layer "F.Fab")
		)
		(fp_line
			(start 0.120396 0.3048)
			(end 0.120396 0.2794)
			(stroke
				(width 0.1)
				(type default)
			)
			(layer "F.Fab")
		)
		(fp_line
			(start 0.12065 -0.3048)
			(end 0.67945 -0.3048)
			(stroke
				(width 0.1)
				(type default)
			)
			(layer "F.Fab")
		)
		(fp_line
			(start 0.12065 -0.2794)
			(end 0.12065 -0.3048)
			(stroke
				(width 0.1)
				(type default)
			)
			(layer "F.Fab")
		)
		(fp_line
			(start 0.67945 -0.3048)
			(end 0.67945 0.3048)
			(stroke
				(width 0.1)
				(type default)
			)
			(layer "F.Fab")
		)
		(fp_line
			(start 0.67945 0.3048)
			(end 0.120396 0.3048)
			(stroke
				(width 0.1)
				(type default)
			)
			(layer "F.Fab")
		)
		(pad "1" smd circle
			(at -0.40005 0)
			(size 0 0)
			(layers "F.Cu" "F.Mask" "F.Paste")
			(net "PD_PIROM_CPU0_ADDR1")
		)
		(pad "2" smd circle
			(at 0.40005 0)
			(size 0 0)
			(layers "F.Cu" "F.Mask" "F.Paste")
			(net "GND")
		)
	)
	(footprint ""
		(layer "F.Cu")
		(at 215.392 -96.103948)
		(property "Reference" "U325"
			(at -5.08 1.04267 0)
			(unlocked yes)
			(layer "F.SilkS")
			(effects
				(font
					(size 0.7874 0.5842)
					(thickness 0.1524)
				)
			)
		)
		(property "Value" ""
			(at 0 0 0)
			(layer "F.Fab")
			(effects
				(font
					(size 1.27 1.27)
				)
			)
		)
		(duplicate_pad_numbers_are_jumpers no)
		(fp_line
			(start -1.949958 -1.610106)
			(end 1.949958 -1.610106)
			(stroke
				(width 0.1524)
				(type default)
			)
			(layer "F.SilkS")
		)
		(fp_line
			(start -1.949958 1.610106)
			(end -1.949958 -1.610106)
			(stroke
				(width 0.1524)
				(type default)
			)
			(layer "F.SilkS")
		)
		(fp_line
			(start 1.949958 -1.560068)
			(end 1.949958 1.610106)
			(stroke
				(width 0.1524)
				(type default)
			)
			(layer "F.SilkS")
		)
		(fp_line
			(start 1.949958 1.610106)
			(end -1.949958 1.610106)
			(stroke
				(width 0.1524)
				(type default)
			)
			(layer "F.SilkS")
		)
		(fp_line
			(start -0.750062 -1.560068)
			(end 0.750062 -1.560068)
			(stroke
				(width 0.1)
				(type default)
			)
			(layer "F.Fab")
		)
		(fp_line
			(start -0.750062 1.560068)
			(end -0.750062 -1.560068)
			(stroke
				(width 0.1)
				(type default)
			)
			(layer "F.Fab")
		)
		(fp_line
			(start 0.750062 -1.560068)
			(end 0.750062 1.560068)
			(stroke
				(width 0.1)
				(type default)
			)
			(layer "F.Fab")
		)
		(fp_line
			(start 0.750062 1.560068)
			(end -0.750062 1.560068)
			(stroke
				(width 0.1)
				(type default)
			)
			(layer "F.Fab")
		)
		(pad "D" smd rect
			(at 1.100074 0 270)
			(size 1.016 1.4224)
			(layers "F.Cu" "F.Mask" "F.Paste")
			(net "IRQ_UV_DETECT_N")
		)
		(pad "G" smd rect
			(at -1.100074 -0.94996 270)
			(size 1.016 1.4224)
			(layers "F.Cu" "F.Mask" "F.Paste")
			(net "A_P12V_STBY_FPH_GATE")
		)
		(pad "S" smd rect
			(at -1.100074 0.94996 270)
			(size 1.016 1.4224)
			(layers "F.Cu" "F.Mask" "F.Paste")
			(net "GND")
		)
	)
	(footprint ""
		(layer "F.Cu")
		(at 109.144308 -74.863452 -90)
		(property "Reference" "R3071"
			(at 0 0 270)
			(layer "F.SilkS")
			(hide yes)
			(effects
				(font
					(size 1.27 1.27)
				)
			)
		)
		(property "Value" ""
			(at 0 0 270)
			(layer "F.Fab")
			(effects
				(font
					(size 1.27 1.27)
				)
			)
		)
		(duplicate_pad_numbers_are_jumpers no)
		(fp_line
			(start -0.7874 0.4064)
			(end -0.7874 -0.4064)
			(stroke
				(width 0.1524)
				(type default)
			)
			(layer "F.SilkS")
		)
		(fp_line
			(start 0.7874 0.4064)
			(end -0.7874 0.4064)
			(stroke
				(width 0.1524)
				(type default)
			)
			(layer "F.SilkS")
		)
		(fp_line
			(start -0.7874 -0.4064)
			(end 0.7874 -0.4064)
			(stroke
				(width 0.1524)
				(type default)
			)
			(layer "F.SilkS")
		)
		(fp_line
			(start 0.7874 -0.4064)
			(end 0.7874 0.4064)
			(stroke
				(width 0.1524)
				(type default)
			)
			(layer "F.SilkS")
		)
		(fp_line
			(start -0.67945 0.3048)
			(end -0.67945 -0.305054)
			(stroke
				(width 0.1)
				(type default)
			)
			(layer "F.Fab")
		)
		(fp_line
			(start -0.12065 0.3048)
			(end -0.67945 0.3048)
			(stroke
				(width 0.1)
				(type default)
			)
			(layer "F.Fab")
		)
		(fp_line
			(start 0.120396 0.3048)
			(end 0.120396 0.2794)
			(stroke
				(width 0.1)
				(type default)
			)
			(layer "F.Fab")
		)
		(fp_line
			(start 0.67945 0.3048)
			(end 0.120396 0.3048)
			(stroke
				(width 0.1)
				(type default)
			)
			(layer "F.Fab")
		)
		(fp_line
			(start -0.12065 0.2794)
			(end -0.12065 0.3048)
			(stroke
				(width 0.1)
				(type default)
			)
			(layer "F.Fab")
		)
		(fp_line
			(start 0.120396 0.2794)
			(end -0.12065 0.2794)
			(stroke
				(width 0.1)
				(type default)
			)
			(layer "F.Fab")
		)
		(fp_line
			(start -0.12065 -0.2794)
			(end 0.12065 -0.2794)
			(stroke
				(width 0.1)
				(type default)
			)
			(layer "F.Fab")
		)
		(fp_line
			(start 0.12065 -0.2794)
			(end 0.12065 -0.3048)
			(stroke
				(width 0.1)
				(type default)
			)
			(layer "F.Fab")
		)
		(fp_line
			(start 0.12065 -0.3048)
			(end 0.67945 -0.3048)
			(stroke
				(width 0.1)
				(type default)
			)
			(layer "F.Fab")
		)
		(fp_line
			(start 0.67945 -0.3048)
			(end 0.67945 0.3048)
			(stroke
				(width 0.1)
				(type default)
			)
			(layer "F.Fab")
		)
		(fp_line
			(start -0.67945 -0.305054)
			(end -0.12065 -0.305054)
			(stroke
				(width 0.1)
				(type default)
			)
			(layer "F.Fab")
		)
		(fp_line
			(start -0.12065 -0.305054)
			(end -0.12065 -0.2794)
			(stroke
				(width 0.1)
				(type default)
			)
			(layer "F.Fab")
		)
		(pad "1" smd circle
			(at -0.40005 0 270)
			(size 0 0)
			(layers "F.Cu" "F.Mask" "F.Paste")
			(net "LED_PWRGD_P1V8_PCH_AUX")
		)
		(pad "2" smd circle
			(at 0.40005 0 270)
			(size 0 0)
			(layers "F.Cu" "F.Mask" "F.Paste")
			(net "P3V3_AUX")
		)
	)
	(footprint ""
		(layer "F.Cu")
		(at 384.56489 -402.371052 -90)
		(property "Reference" "C942"
			(at 0 0 270)
			(layer "F.SilkS")
			(hide yes)
			(effects
				(font
					(size 1.27 1.27)
				)
			)
		)
		(property "Value" ""
			(at 0 0 270)
			(layer "F.Fab")
			(effects
				(font
					(size 1.27 1.27)
				)
			)
		)
		(duplicate_pad_numbers_are_jumpers no)
		(fp_line
			(start -0.299974 0.150114)
			(end -0.299974 -0.150114)
			(stroke
				(width 0.1)
				(type default)
			)
			(layer "F.Fab")
		)
		(fp_line
			(start 0.299974 0.150114)
			(end -0.299974 0.150114)
			(stroke
				(width 0.1)
				(type default)
			)
			(layer "F.Fab")
		)
		(fp_line
			(start -0.299974 -0.150114)
			(end 0.299974 -0.150114)
			(stroke
				(width 0.1)
				(type default)
			)
			(layer "F.Fab")
		)
		(fp_line
			(start 0.299974 -0.150114)
			(end 0.299974 0.150114)
			(stroke
				(width 0.1)
				(type default)
			)
			(layer "F.Fab")
		)
		(pad "1" smd rect
			(at -0.2667 0 270)
			(size 0.3048 0.381)
			(layers "F.Cu" "F.Mask" "F.Paste")
			(net "P5E_CPU0_PE2_TX_C_DN<11>")
		)
		(pad "2" smd rect
			(at 0.2667 0 270)
			(size 0.3048 0.381)
			(layers "F.Cu" "F.Mask" "F.Paste")
			(net "P5E_CPU0_PE2_TX_DN<11>")
		)
	)
	(footprint ""
		(layer "F.Cu")
		(at 293.078916 -367.345976)
		(property "Reference" "PC723_P0_4"
			(at 0 0 0)
			(layer "F.SilkS")
			(hide yes)
			(effects
				(font
					(size 1.27 1.27)
				)
			)
		)
		(property "Value" ""
			(at 0 0 0)
			(layer "F.Fab")
			(effects
				(font
					(size 1.27 1.27)
				)
			)
		)
		(duplicate_pad_numbers_are_jumpers no)
		(fp_line
			(start -1.524 -0.762)
			(end 1.524 -0.762)
			(stroke
				(width 0.1524)
				(type default)
			)
			(layer "F.SilkS")
		)
		(fp_line
			(start -1.524 0.762)
			(end -1.524 -0.762)
			(stroke
				(width 0.1524)
				(type default)
			)
			(layer "F.SilkS")
		)
		(fp_line
			(start 1.524 -0.762)
			(end 1.524 0.762)
			(stroke
				(width 0.1524)
				(type default)
			)
			(layer "F.SilkS")
		)
		(fp_line
			(start 1.524 0.762)
			(end -1.524 0.762)
			(stroke
				(width 0.1524)
				(type default)
			)
			(layer "F.SilkS")
		)
		(fp_line
			(start -1.1049 -0.724916)
			(end -1.1049 0.724916)
			(stroke
				(width 0.1)
				(type default)
			)
			(layer "F.Fab")
		)
		(fp_line
			(start -1.1049 0.724916)
			(end 1.1049 0.724916)
			(stroke
				(width 0.1)
				(type default)
			)
			(layer "F.Fab")
		)
		(fp_line
			(start 1.1049 -0.724916)
			(end -1.1049 -0.724916)
			(stroke
				(width 0.1)
				(type default)
			)
			(layer "F.Fab")
		)
		(fp_line
			(start 1.1049 0.724916)
			(end 1.1049 -0.724916)
			(stroke
				(width 0.1)
				(type default)
			)
			(layer "F.Fab")
		)
		(pad "1" smd rect
			(at -0.889 0 180)
			(size 1.016 1.27)
			(layers "F.Cu" "F.Mask" "F.Paste")
			(net "SW_P12V_PVCCFA_EHV_FIVRA_CPU0_L")
		)
		(pad "2" smd rect
			(at 0.889 0 180)
			(size 1.016 1.27)
			(layers "F.Cu" "F.Mask" "F.Paste")
			(net "GND")
		)
	)
	(footprint ""
		(layer "F.Cu")
		(at 89.5604 -38.659308)
		(property "Reference" "U53"
			(at -0.28448 -2.553208 0)
			(unlocked yes)
			(layer "F.SilkS")
			(effects
				(font
					(size 0.7874 0.5842)
					(thickness 0.1524)
				)
				(justify left)
			)
		)
		(property "Value" ""
			(at 0 0 0)
			(layer "F.Fab")
			(effects
				(font
					(size 1.27 1.27)
				)
			)
		)
		(duplicate_pad_numbers_are_jumpers no)
		(fp_line
			(start -1.733296 -1.549908)
			(end -1.733296 1.549908)
			(stroke
				(width 0.1524)
				(type default)
			)
			(layer "F.SilkS")
		)
		(fp_line
			(start -1.733296 1.549908)
			(end 1.733296 1.549908)
			(stroke
				(width 0.1524)
				(type default)
			)
			(layer "F.SilkS")
		)
		(fp_line
			(start -0.660908 -1.549908)
			(end -1.733296 -1.549908)
			(stroke
				(width 0.1524)
				(type default)
			)
			(layer "F.SilkS")
		)
		(fp_line
			(start 0 -0.889)
			(end -0.660908 -1.549908)
			(stroke
				(width 0.1524)
				(type default)
			)
			(layer "F.SilkS")
		)
		(fp_line
			(start 0.660908 -1.549908)
			(end 0 -0.889)
			(stroke
				(width 0.1524)
				(type default)
			)
			(layer "F.SilkS")
		)
		(fp_line
			(start 1.733296 -1.549908)
			(end 0.660908 -1.549908)
			(stroke
				(width 0.1524)
				(type default)
			)
			(layer "F.SilkS")
		)
		(fp_line
			(start 1.733296 1.549908)
			(end 1.733296 -1.549908)
			(stroke
				(width 0.1524)
				(type default)
			)
			(layer "F.SilkS")
		)
		(fp_poly
			(pts
				(xy -0.92456 -2.2479) (xy -1.17856 -1.7399) (xy -1.43256 -2.2479)
			)
			(stroke
				(width 0)
				(type default)
			)
			(fill yes)
			(layer "F.SilkS")
		)
		(fp_line
			(start -0.849884 -1.549908)
			(end -0.849884 1.549908)
			(stroke
				(width 0.1)
				(type default)
			)
			(layer "F.Fab")
		)
		(fp_line
			(start -0.849884 1.549908)
			(end 0.849884 1.549908)
			(stroke
				(width 0.1)
				(type default)
			)
			(layer "F.Fab")
		)
		(fp_line
			(start 0.849884 -1.549908)
			(end -0.849884 -1.549908)
			(stroke
				(width 0.1)
				(type default)
			)
			(layer "F.Fab")
		)
		(fp_line
			(start 0.849884 1.549908)
			(end 0.849884 -1.549908)
			(stroke
				(width 0.1)
				(type default)
			)
			(layer "F.Fab")
		)
		(fp_poly
			(pts
				(xy -2.4384 -1.20396) (xy -2.4384 -0.69596) (xy -1.9304 -0.94996)
			)
			(stroke
				(width 0)
				(type default)
			)
			(fill yes)
			(layer "F.Fab")
		)
		(pad "1" smd rect
			(at -1.199896 -0.94996 270)
			(size 0.5588 0.8128)
			(layers "F.Cu" "F.Mask" "F.Paste")
			(net "HP_LVC3_OCP_V3_2_PWRGD_R")
		)
		(pad "2" smd rect
			(at -1.199896 0 270)
			(size 0.5588 0.8128)
			(layers "F.Cu" "F.Mask" "F.Paste")
			(net "RST_OCP_V3_2_N")
		)
		(pad "3" smd rect
			(at -1.199896 0.94996 270)
			(size 0.5588 0.8128)
			(layers "F.Cu" "F.Mask" "F.Paste")
			(net "GND")
		)
		(pad "4" smd rect
			(at 1.199896 0.94996 270)
			(size 0.5588 0.8128)
			(layers "F.Cu" "F.Mask" "F.Paste")
			(net "RST_HP_OCP_V3_2_N")
		)
		(pad "5" smd rect
			(at 1.199896 -0.94996 270)
			(size 0.5588 0.8128)
			(layers "F.Cu" "F.Mask" "F.Paste")
			(net "P3V3_AUX")
		)
	)
	(footprint ""
		(layer "F.Cu")
		(at 186.437524 -353.650296 -90)
		(property "Reference" "PC1193_P1_3"
			(at 0 0 270)
			(layer "F.SilkS")
			(hide yes)
			(effects
				(font
					(size 1.27 1.27)
				)
			)
		)
		(property "Value" ""
			(at 0 0 270)
			(layer "F.Fab")
			(effects
				(font
					(size 1.27 1.27)
				)
			)
		)
		(duplicate_pad_numbers_are_jumpers no)
		(fp_line
			(start -0.7874 0.4064)
			(end -0.7874 -0.4064)
			(stroke
				(width 0.1524)
				(type default)
			)
			(layer "F.SilkS")
		)
		(fp_line
			(start 0.7874 0.4064)
			(end -0.7874 0.4064)
			(stroke
				(width 0.1524)
				(type default)
			)
			(layer "F.SilkS")
		)
		(fp_line
			(start -0.7874 -0.4064)
			(end 0.7874 -0.4064)
			(stroke
				(width 0.1524)
				(type default)
			)
			(layer "F.SilkS")
		)
		(fp_line
			(start 0.7874 -0.4064)
			(end 0.7874 0.4064)
			(stroke
				(width 0.1524)
				(type default)
			)
			(layer "F.SilkS")
		)
		(fp_line
			(start -0.67945 0.3048)
			(end -0.67945 -0.305054)
			(stroke
				(width 0.1)
				(type default)
			)
			(layer "F.Fab")
		)
		(fp_line
			(start -0.12065 0.3048)
			(end -0.67945 0.3048)
			(stroke
				(width 0.1)
				(type default)
			)
			(layer "F.Fab")
		)
		(fp_line
			(start 0.120396 0.3048)
			(end 0.120396 0.2794)
			(stroke
				(width 0.1)
				(type default)
			)
			(layer "F.Fab")
		)
		(fp_line
			(start 0.67945 0.3048)
			(end 0.120396 0.3048)
			(stroke
				(width 0.1)
				(type default)
			)
			(layer "F.Fab")
		)
		(fp_line
			(start -0.12065 0.2794)
			(end -0.12065 0.3048)
			(stroke
				(width 0.1)
				(type default)
			)
			(layer "F.Fab")
		)
		(fp_line
			(start 0.120396 0.2794)
			(end -0.12065 0.2794)
			(stroke
				(width 0.1)
				(type default)
			)
			(layer "F.Fab")
		)
		(fp_line
			(start -0.12065 -0.2794)
			(end 0.12065 -0.2794)
			(stroke
				(width 0.1)
				(type default)
			)
			(layer "F.Fab")
		)
		(fp_line
			(start 0.12065 -0.2794)
			(end 0.12065 -0.3048)
			(stroke
				(width 0.1)
				(type default)
			)
			(layer "F.Fab")
		)
		(fp_line
			(start 0.12065 -0.3048)
			(end 0.67945 -0.3048)
			(stroke
				(width 0.1)
				(type default)
			)
			(layer "F.Fab")
		)
		(fp_line
			(start 0.67945 -0.3048)
			(end 0.67945 0.3048)
			(stroke
				(width 0.1)
				(type default)
			)
			(layer "F.Fab")
		)
		(fp_line
			(start -0.67945 -0.305054)
			(end -0.12065 -0.305054)
			(stroke
				(width 0.1)
				(type default)
			)
			(layer "F.Fab")
		)
		(fp_line
			(start -0.12065 -0.305054)
			(end -0.12065 -0.2794)
			(stroke
				(width 0.1)
				(type default)
			)
			(layer "F.Fab")
		)
		(pad "1" smd circle
			(at -0.40005 0 270)
			(size 0 0)
			(layers "F.Cu" "F.Mask" "F.Paste")
			(net "SW_P12V_PVCCFA_EHV_FIVRA_CPU1_R")
		)
		(pad "2" smd circle
			(at 0.40005 0 270)
			(size 0 0)
			(layers "F.Cu" "F.Mask" "F.Paste")
			(net "GND")
		)
	)
)
